# T6G (Grand Teton) — schematic netlist excerpt (pin names and nets, part order shuffled) for the footprints in the layout excerpt that follows; sources: Cadence DE-HDL packaged netlist, KiCad conversion of 04192023_DAF0TMB3IC0_F0TG_MB_C_brd_V02_OCP.brd

R3630  Q_RES  0 5% EMPTY  pkg 0402LF  page 141 : A = P12V_OCP_V3_2_EN_R ; B = P12V_OCP_V3_2_EN_2_R3
R3862  Q_RES  0 5% EMPTY  pkg 0402LF  page 257 : A = P12V_OCP_V3_2_ISENSE_MPS_TIC ; B = P12V_OCP_V3_2_ISENSE_TIC
C908  Q_CAP_DIFFBUS  DIFF BUS_0.22UF 6.3V 20% X6S  pkg C0201  page 63 : \1\ = P5E_CPU0_P0_TX_C_DN<12> ; \2\ = P5E_CPU0_P0_TX_DN<12>

(kicad_pcb
	(version 20260206)
	(generator "pcbnew")
	(generator_version "10.0")
	(general
		(thickness 1.6)
		(legacy_teardrops no)
	)
	(paper "A4")
	(title_block
		(title "04192023_DAF0TMB3IC0_F0TG_MB_C_brd_V02_OCP.brd")
		(comment 1 "Grand Teton / footprints 3604-3606 of 8354")
	)
	(layers
		(0 "F.Cu" signal "TOP")
		(4 "In1.Cu" signal "GND")
		(6 "In2.Cu" signal "IN1")
		(8 "In3.Cu" signal "GND1")
		(10 "In4.Cu" signal "IN2")
		(12 "In5.Cu" signal "GND2")
		(14 "In6.Cu" signal "IN3")
		(16 "In7.Cu" signal "GND3")
		(18 "In8.Cu" signal "VCC")
		(20 "In9.Cu" signal "VCC1")
		(22 "In10.Cu" signal "GND4")
		(24 "In11.Cu" signal "IN4")
		(26 "In12.Cu" signal "GND5")
		(28 "In13.Cu" signal "IN5")
		(30 "In14.Cu" signal "GND6")
		(32 "In15.Cu" signal "IN6")
		(34 "In16.Cu" signal "GND7")
		(2 "B.Cu" signal "BOTTOM")
		(9 "F.Adhes" user "F.Adhesive")
		(11 "B.Adhes" user "B.Adhesive")
		(13 "F.Paste" user "Package Geometry/Pastemask Top")
		(15 "B.Paste" user "Package Geometry/Pastemask Bottom")
		(5 "F.SilkS" user "Ref Des/Silkscreen Top")
		(7 "B.SilkS" user "Ref Des/Silkscreen Bottom")
		(1 "F.Mask" user "Board Geometry/Soldermask Top")
		(3 "B.Mask" user "Board Geometry/Soldermask Bottom")
		(17 "Dwgs.User" user "User.Drawings")
		(19 "Cmts.User" user "User.Comments")
		(21 "Eco1.User" user "User.Eco1")
		(23 "Eco2.User" user "User.Eco2")
		(25 "Edge.Cuts" user "Board Geometry/Outline")
		(27 "Margin" user)
		(31 "F.CrtYd" user "Package Geometry/Place Bound Top")
		(29 "B.CrtYd" user "Package Geometry/Place Bound Bottom")
		(35 "F.Fab" user "Ref Des/Assembly Top")
		(33 "B.Fab" user "Ref Des/Assembly Bottom")
	)
	(footprint ""
		(layer "F.Cu")
		(at 323.637148 -44.716954 180)
		(property "Reference" "R3862"
			(at 0 0 180)
			(layer "F.SilkS")
			(hide yes)
			(effects
				(font
					(size 1.27 1.27)
				)
			)
		)
		(property "Value" ""
			(at 0 0 180)
			(layer "F.Fab")
			(effects
				(font
					(size 1.27 1.27)
				)
			)
		)
		(duplicate_pad_numbers_are_jumpers no)
		(fp_line
			(start 0.7874 0.4064)
			(end -0.7874 0.4064)
			(stroke
				(width 0.1524)
				(type default)
			)
			(layer "F.SilkS")
		)
		(fp_line
			(start 0.7874 -0.4064)
			(end 0.7874 0.4064)
			(stroke
				(width 0.1524)
				(type default)
			)
			(layer "F.SilkS")
		)
		(fp_line
			(start -0.7874 0.4064)
			(end -0.7874 -0.4064)
			(stroke
				(width 0.1524)
				(type default)
			)
			(layer "F.SilkS")
		)
		(fp_line
			(start -0.7874 -0.4064)
			(end 0.7874 -0.4064)
			(stroke
				(width 0.1524)
				(type default)
			)
			(layer "F.SilkS")
		)
		(fp_line
			(start 0.67945 0.3048)
			(end 0.120396 0.3048)
			(stroke
				(width 0.1)
				(type default)
			)
			(layer "F.Fab")
		)
		(fp_line
			(start 0.67945 -0.3048)
			(end 0.67945 0.3048)
			(stroke
				(width 0.1)
				(type default)
			)
			(layer "F.Fab")
		)
		(fp_line
			(start 0.12065 -0.2794)
			(end 0.12065 -0.3048)
			(stroke
				(width 0.1)
				(type default)
			)
			(layer "F.Fab")
		)
		(fp_line
			(start 0.12065 -0.3048)
			(end 0.67945 -0.3048)
			(stroke
				(width 0.1)
				(type default)
			)
			(layer "F.Fab")
		)
		(fp_line
			(start 0.120396 0.3048)
			(end 0.120396 0.2794)
			(stroke
				(width 0.1)
				(type default)
			)
			(layer "F.Fab")
		)
		(fp_line
			(start 0.120396 0.2794)
			(end -0.12065 0.2794)
			(stroke
				(width 0.1)
				(type default)
			)
			(layer "F.Fab")
		)
		(fp_line
			(start -0.12065 0.3048)
			(end -0.67945 0.3048)
			(stroke
				(width 0.1)
				(type default)
			)
			(layer "F.Fab")
		)
		(fp_line
			(start -0.12065 0.2794)
			(end -0.12065 0.3048)
			(stroke
				(width 0.1)
				(type default)
			)
			(layer "F.Fab")
		)
		(fp_line
			(start -0.12065 -0.2794)
			(end 0.12065 -0.2794)
			(stroke
				(width 0.1)
				(type default)
			)
			(layer "F.Fab")
		)
		(fp_line
			(start -0.12065 -0.305054)
			(end -0.12065 -0.2794)
			(stroke
				(width 0.1)
				(type default)
			)
			(layer "F.Fab")
		)
		(fp_line
			(start -0.67945 0.3048)
			(end -0.67945 -0.305054)
			(stroke
				(width 0.1)
				(type default)
			)
			(layer "F.Fab")
		)
		(fp_line
			(start -0.67945 -0.305054)
			(end -0.12065 -0.305054)
			(stroke
				(width 0.1)
				(type default)
			)
			(layer "F.Fab")
		)
		(pad "1" smd rect
			(at -0.40005 0)
			(size 0.4572 0.508)
			(layers "F.Cu" "F.Mask" "F.Paste")
			(net "P12V_OCP_V3_2_ISENSE_MPS_TIC")
		)
		(pad "2" smd rect
			(at 0.40005 0)
			(size 0.4572 0.508)
			(layers "F.Cu" "F.Mask" "F.Paste")
			(net "P12V_OCP_V3_2_ISENSE_TIC")
		)
	)
	(footprint ""
		(layer "F.Cu")
		(at 322.027296 -378.95403 -90)
		(property "Reference" "C908"
			(at 0 0 270)
			(layer "F.SilkS")
			(hide yes)
			(effects
				(font
					(size 1.27 1.27)
				)
			)
		)
		(property "Value" ""
			(at 0 0 270)
			(layer "F.Fab")
			(effects
				(font
					(size 1.27 1.27)
				)
			)
		)
		(duplicate_pad_numbers_are_jumpers no)
		(fp_line
			(start -0.299974 0.150114)
			(end -0.299974 -0.150114)
			(stroke
				(width 0.1)
				(type default)
			)
			(layer "F.Fab")
		)
		(fp_line
			(start 0.299974 0.150114)
			(end -0.299974 0.150114)
			(stroke
				(width 0.1)
				(type default)
			)
			(layer "F.Fab")
		)
		(fp_line
			(start -0.299974 -0.150114)
			(end 0.299974 -0.150114)
			(stroke
				(width 0.1)
				(type default)
			)
			(layer "F.Fab")
		)
		(fp_line
			(start 0.299974 -0.150114)
			(end 0.299974 0.150114)
			(stroke
				(width 0.1)
				(type default)
			)
			(layer "F.Fab")
		)
		(pad "1" smd rect
			(at -0.2667 0 270)
			(size 0.3048 0.381)
			(layers "F.Cu" "F.Mask" "F.Paste")
			(net "P5E_CPU0_P0_TX_C_DN<12>")
		)
		(pad "2" smd rect
			(at 0.2667 0 270)
			(size 0.3048 0.381)
			(layers "F.Cu" "F.Mask" "F.Paste")
			(net "P5E_CPU0_P0_TX_DN<12>")
		)
	)
	(footprint ""
		(layer "F.Cu")
		(at 70.052438 -31.887922 -90)
		(property "Reference" "R3630"
			(at 0 0 270)
			(layer "F.SilkS")
			(hide yes)
			(effects
				(font
					(size 1.27 1.27)
				)
			)
		)
		(property "Value" ""
			(at 0 0 270)
			(layer "F.Fab")
			(effects
				(font
					(size 1.27 1.27)
				)
			)
		)
		(duplicate_pad_numbers_are_jumpers no)
		(fp_line
			(start -0.7874 0.4064)
			(end -0.7874 -0.4064)
			(stroke
				(width 0.1524)
				(type default)
			)
			(layer "F.SilkS")
		)
		(fp_line
			(start 0.7874 0.4064)
			(end -0.7874 0.4064)
			(stroke
				(width 0.1524)
				(type default)
			)
			(layer "F.SilkS")
		)
		(fp_line
			(start -0.7874 -0.4064)
			(end 0.7874 -0.4064)
			(stroke
				(width 0.1524)
				(type default)
			)
			(layer "F.SilkS")
		)
		(fp_line
			(start 0.7874 -0.4064)
			(end 0.7874 0.4064)
			(stroke
				(width 0.1524)
				(type default)
			)
			(layer "F.SilkS")
		)
		(fp_line
			(start -0.67945 0.3048)
			(end -0.67945 -0.305054)
			(stroke
				(width 0.1)
				(type default)
			)
			(layer "F.Fab")
		)
		(fp_line
			(start -0.12065 0.3048)
			(end -0.67945 0.3048)
			(stroke
				(width 0.1)
				(type default)
			)
			(layer "F.Fab")
		)
		(fp_line
			(start 0.120396 0.3048)
			(end 0.120396 0.2794)
			(stroke
				(width 0.1)
				(type default)
			)
			(layer "F.Fab")
		)
		(fp_line
			(start 0.67945 0.3048)
			(end 0.120396 0.3048)
			(stroke
				(width 0.1)
				(type default)
			)
			(layer "F.Fab")
		)
		(fp_line
			(start -0.12065 0.2794)
			(end -0.12065 0.3048)
			(stroke
				(width 0.1)
				(type default)
			)
			(layer "F.Fab")
		)
		(fp_line
			(start 0.120396 0.2794)
			(end -0.12065 0.2794)
			(stroke
				(width 0.1)
				(type default)
			)
			(layer "F.Fab")
		)
		(fp_line
			(start -0.12065 -0.2794)
			(end 0.12065 -0.2794)
			(stroke
				(width 0.1)
				(type default)
			)
			(layer "F.Fab")
		)
		(fp_line
			(start 0.12065 -0.2794)
			(end 0.12065 -0.3048)
			(stroke
				(width 0.1)
				(type default)
			)
			(layer "F.Fab")
		)
		(fp_line
			(start 0.12065 -0.3048)
			(end 0.67945 -0.3048)
			(stroke
				(width 0.1)
				(type default)
			)
			(layer "F.Fab")
		)
		(fp_line
			(start 0.67945 -0.3048)
			(end 0.67945 0.3048)
			(stroke
				(width 0.1)
				(type default)
			)
			(layer "F.Fab")
		)
		(fp_line
			(start -0.67945 -0.305054)
			(end -0.12065 -0.305054)
			(stroke
				(width 0.1)
				(type default)
			)
			(layer "F.Fab")
		)
		(fp_line
			(start -0.12065 -0.305054)
			(end -0.12065 -0.2794)
			(stroke
				(width 0.1)
				(type default)
			)
			(layer "F.Fab")
		)
		(pad "1" smd circle
			(at -0.40005 0 270)
			(size 0 0)
			(layers "F.Cu" "F.Mask" "F.Paste")
			(net "P12V_OCP_V3_2_EN_R")
		)
		(pad "2" smd circle
			(at 0.40005 0 270)
			(size 0 0)
			(layers "F.Cu" "F.Mask" "F.Paste")
			(net "P12V_OCP_V3_2_EN_2_R3")
		)
	)
)
